(kicad_pcb
	(version 20221018)
	(generator pcbnew)
	(general
    (thickness 1.6)
  )
	(paper "A4")
	(title_block
    (title "NUC Computer Cluster Power Breakout HW")
    (date "2023-10-18")
    (rev "1.4.3")
    (company "Antmicro Ltd.")
		(comment 9 "footprints 55-61 of 234")
	)
	(layers
    (0 "F.Cu" mixed)
    (1 "In1.Cu" power)
    (2 "In2.Cu" mixed)
    (31 "B.Cu" power)
    (32 "B.Adhes" user "B.Adhesive")
    (33 "F.Adhes" user "F.Adhesive")
    (34 "B.Paste" user)
    (35 "F.Paste" user)
    (36 "B.SilkS" user "B.Silkscreen")
    (37 "F.SilkS" user "F.Silkscreen")
    (38 "B.Mask" user)
    (39 "F.Mask" user)
    (40 "Dwgs.User" user "User.Drawings")
    (41 "Cmts.User" user "User.Comments")
    (42 "Eco1.User" user "User.Eco1")
    (43 "Eco2.User" user "User.Eco2")
    (44 "Edge.Cuts" user)
    (45 "Margin" user)
    (46 "B.CrtYd" user "B.Courtyard")
    (47 "F.CrtYd" user "F.Courtyard")
    (48 "B.Fab" user)
    (49 "F.Fab" user)
  )
	(footprint "antmicro-footprints:TPD2E009DRTR" (layer "F.Cu")
    (at 181.3875 113.45 180)
    (property "Author" "Antmicro")
    (property "License" "Apache-2.0")
    (property "MPN" "PESD5V0S2BQA")
    (property "Manufacturer" "Nexperia")
    (property "Sheetfile" "ftdi-module.kicad_sch")
    (property "Sheetname" "FTDI")
    (property "ki_description" "TVS diode array, 30 kV, SOT-1215, 5V, 45 pF")
    (property "ki_keywords" "SMT, DIODE, SEMICONDUCTOR, TVS, ESD")
    (attr smd)
    (fp_text reference "D1" (at 2.6875 -0.6 180) (layer "F.SilkS")
        (effects (font (size 0.7 0.7) (thickness 0.15)) (justify left bottom))
    )
    (fp_text value "PESD5V0S2BQA" (at 5.608 1.306 180) (layer "F.Fab")
        (effects (font (size 0.7 0.7) (thickness 0.15)) (justify left bottom))
    )
    (fp_text user "License: Apache-2.0" (at -0.949 5.706 180) (layer "F.Fab") hide
        (effects (font (size 0.7 0.7) (thickness 0.15)) (justify left bottom))
    )
    (fp_text user "${REFERENCE}" (at -0.949 4.506 180) (layer "F.Fab") hide
        (effects (font (size 0.7 0.7) (thickness 0.15)) (justify left bottom))
    )
    (fp_text user "Author: Antmicro" (at -0.949 3.306 180) (layer "F.Fab") hide
        (effects (font (size 0.7 0.7) (thickness 0.15)) (justify left bottom))
    )
    (fp_line (start 0.03 -0.499) (end 0.4 -0.499)
      (stroke (width 0.15) (type solid)) (layer "F.SilkS"))
    (fp_line (start 0.03 0.499) (end 0.4 0.499)
      (stroke (width 0.15) (type solid)) (layer "F.SilkS"))
    (fp_line (start 0.4 -0.419) (end 0.4 -0.499)
      (stroke (width 0.15) (type solid)) (layer "F.SilkS"))
    (fp_line (start 0.4 0.42) (end 0.4 0.499)
      (stroke (width 0.15) (type solid)) (layer "F.SilkS"))
    (fp_circle (center -0.5 -0.6) (end -0.45 -0.6)
      (stroke (width 0.15) (type solid)) (fill solid) (layer "F.SilkS"))
    (fp_rect (start -0.8 -0.59) (end 0.8 0.59)
      (stroke (width 0.05) (type solid)) (fill none) (layer "F.CrtYd"))
    (fp_line (start -0.4 -0.499) (end 0.4 -0.499)
      (stroke (width 0.15) (type solid)) (layer "F.Fab"))
    (fp_line (start -0.4 0.499) (end -0.4 -0.499)
      (stroke (width 0.15) (type solid)) (layer "F.Fab"))
    (fp_line (start 0.4 -0.499) (end 0.4 0.499)
      (stroke (width 0.15) (type solid)) (layer "F.Fab"))
    (fp_line (start 0.4 0.499) (end -0.4 0.499)
      (stroke (width 0.15) (type solid)) (layer "F.Fab"))
    (pad "1" smd rect (at -0.52 -0.349 180) (size 0.46 0.2) (layers "F.Cu" "F.Paste" "F.Mask")
      (net 15 "/FTDI/USB_D-") (pinfunction "IO1") (pintype "passive"))
    (pad "2" smd rect (at -0.52 0.348 180) (size 0.46 0.2) (layers "F.Cu" "F.Paste" "F.Mask")
      (net 14 "/FTDI/USB_D+") (pinfunction "IO2") (pintype "passive"))
    (pad "3" smd rect (at 0.52 0 180) (size 0.46 0.2) (layers "F.Cu" "F.Paste" "F.Mask")
      (net 77 "GNDD") (pinfunction "GND") (pintype "passive"))
  )
	(footprint "antmicro-footprints:LED_0603_1608Metric_G" (layer "F.Cu")
    (at 181.75 108.45 -90)
    (descr "LED SMD 0603 Green")
    (tags "LED SMD 0603 Green")
    (property "Author" "Antmicro")
    (property "Color" "Green")
    (property "License" "Apache-2.0")
    (property "MPN" "LG L29K-G2J1-24-Z")
    (property "Manufacturer" "OSRAM")
    (property "Sheetfile" "ftdi-module.kicad_sch")
    (property "Sheetname" "FTDI")
    (property "ki_description" "LED, Green, SMD, 0603, 20 mA, 1.7 V, 570 nm")
    (property "ki_keywords" "SMT, DIODE, SEMICONDUCTOR, LED")
    (attr smd)
    (fp_text reference "D2" (at -1.35 0.75) (layer "F.SilkS")
        (effects (font (size 0.7 0.7) (thickness 0.15)) (justify left bottom))
    )
    (fp_text value "LED_G_0603_LG_L29K-G2J1-24-Z" (at -0.001 1.599 -90) (layer "F.Fab")
        (effects (font (size 0.7 0.7) (thickness 0.15)) (justify left bottom))
    )
    (fp_text user "Author: Antmicro" (at -1.4224 4.799 -90) (layer "F.Fab") hide
        (effects (font (size 0.7 0.7) (thickness 0.15)) (justify left bottom))
    )
    (fp_text user "${REFERENCE}" (at -1.4224 5.999 -90) (layer "F.Fab") hide
        (effects (font (size 0.7 0.7) (thickness 0.15)) (justify left bottom))
    )
    (fp_text user "License: Apache-2.0" (at -1.4224 3.599 -90) (layer "F.Fab") hide
        (effects (font (size 0.7 0.7) (thickness 0.15)) (justify left bottom))
    )
    (fp_line (start -1.18 -0.319) (end -1.18 0.321)
      (stroke (width 0.15) (type solid)) (layer "F.SilkS"))
    (fp_line (start -0.094672 0.001008) (end -0.24 0.001008)
      (stroke (width 0.1) (type solid)) (layer "F.SilkS"))
    (fp_line (start -0.094672 0.001008) (end 0.105328 -0.198992)
      (stroke (width 0.1) (type solid)) (layer "F.SilkS"))
    (fp_line (start -0.094672 0.201008) (end -0.094672 -0.198992)
      (stroke (width 0.1) (type solid)) (layer "F.SilkS"))
    (fp_line (start 0.105328 0.001008) (end 0.24 0.001)
      (stroke (width 0.1) (type solid)) (layer "F.SilkS"))
    (fp_line (start 0.105328 0.201008) (end -0.094672 0.001008)
      (stroke (width 0.1) (type solid)) (layer "F.SilkS"))
    (fp_line (start 0.105328 0.201008) (end 0.105328 -0.198992)
      (stroke (width 0.1) (type solid)) (layer "F.SilkS"))
    (fp_line (start 0.22 -0.35) (end -0.22 -0.35)
      (stroke (width 0.15) (type solid)) (layer "F.SilkS"))
    (fp_line (start 0.22 0.35) (end -0.22 0.35)
      (stroke (width 0.15) (type solid)) (layer "F.SilkS"))
    (fp_rect (start 1.25 0.65) (end -1.25 -0.65)
      (stroke (width 0.05) (type solid)) (fill none) (layer "F.CrtYd"))
    (fp_line (start -0.199 -0.202) (end -0.199 0.1)
      (stroke (width 0.15) (type solid)) (layer "F.Fab"))
    (fp_line (start -0.199 0) (end -0.597 0)
      (stroke (width 0.15) (type solid)) (layer "F.Fab"))
    (fp_line (start -0.199 0.2) (end -0.199 0.1)
      (stroke (width 0.15) (type solid)) (layer "F.Fab"))
    (fp_line (start -0.101 0) (end 0.201 0.2)
      (stroke (width 0.15) (type solid)) (layer "F.Fab"))
    (fp_line (start 0.201 -0.202) (end -0.101 0)
      (stroke (width 0.15) (type solid)) (layer "F.Fab"))
    (fp_line (start 0.201 0) (end 0.201 -0.202)
      (stroke (width 0.15) (type solid)) (layer "F.Fab"))
    (fp_line (start 0.201 0.2) (end 0.201 0)
      (stroke (width 0.15) (type solid)) (layer "F.Fab"))
    (fp_line (start 0.599 0) (end 0.201 0)
      (stroke (width 0.15) (type solid)) (layer "F.Fab"))
    (fp_rect (start 0.848 0.4) (end -0.85 -0.402)
      (stroke (width 0.15) (type solid)) (fill none) (layer "F.Fab"))
    (pad "1" smd roundrect (at -0.7 0 90) (size 0.8 1) (layers "F.Cu" "F.Paste" "F.Mask") (roundrect_rratio 0.2)
      (net 77 "GNDD") (pinfunction "C") (pintype "passive"))
    (pad "2" smd roundrect (at 0.7 0 90) (size 0.8 1) (layers "F.Cu" "F.Paste" "F.Mask") (roundrect_rratio 0.2)
      (net 35 "Net-(D2-A)") (pinfunction "A") (pintype "passive"))
  )
	(footprint "antmicro-footprints:FB_0603_1608Metric" (layer "F.Cu")
    (at 183.2 108.45 90)
    (property "Author" "Antmicro")
    (property "Current" "")
    (property "License" "Apache-2.0")
    (property "MPN" "BLM18AG601SN1D")
    (property "Manufacturer" "Murata")
    (property "Sheetfile" "ftdi-module.kicad_sch")
    (property "Sheetname" "FTDI")
    (property "Val" "600Z/0.5A")
    (property "ki_description" "Ferrite Bead, 0603 [1608 Metric], 600 ohm, 500 mA, BLM18A, 0.38 ohm, ± 25%, General use")
    (property "ki_keywords" "0603, SMT, FERRITE BEAD, PASSIVE")
    (attr smd)
    (fp_text reference "FB3" (at 1.25 0.45 90) (layer "F.SilkS")
        (effects (font (size 0.7 0.7) (thickness 0.15)) (justify left bottom))
    )
    (fp_text value "FB_600Z_0.5A_Murata-BLM18AG_0603" (at 0 1.5 90) (layer "F.Fab")
        (effects (font (size 0.7 0.7) (thickness 0.15)) (justify left bottom))
    )
    (fp_text user "${REFERENCE}" (at -1.653 4.6 90) (layer "F.Fab") hide
        (effects (font (size 0.7 0.7) (thickness 0.15)) (justify left bottom))
    )
    (fp_text user "Author: Antmicro" (at -1.653 3.162 90) (layer "F.Fab") hide
        (effects (font (size 0.7 0.7) (thickness 0.15)) (justify left bottom))
    )
    (fp_text user "License: Apache-2.0" (at -1.653 5.9 90) (layer "F.Fab") hide
        (effects (font (size 0.7 0.7) (thickness 0.15)) (justify left bottom))
    )
    (fp_line (start -0.15 -0.4) (end 0.15 -0.4)
      (stroke (width 0.15) (type solid)) (layer "F.SilkS"))
    (fp_line (start -0.15 0.4) (end 0.15 0.4)
      (stroke (width 0.15) (type solid)) (layer "F.SilkS"))
    (fp_rect (start -1.25 -0.65) (end 1.25 0.65)
      (stroke (width 0.05) (type solid)) (fill none) (layer "F.CrtYd"))
    (fp_line (start -0.803 0.406) (end -0.803 -0.408)
      (stroke (width 0.15) (type solid)) (layer "F.Fab"))
    (fp_line (start 0.8 -0.408) (end -0.803 -0.408)
      (stroke (width 0.15) (type solid)) (layer "F.Fab"))
    (fp_line (start 0.8 -0.408) (end 0.8 0.406)
      (stroke (width 0.15) (type solid)) (layer "F.Fab"))
    (fp_line (start 0.8 0.406) (end -0.803 0.406)
      (stroke (width 0.15) (type solid)) (layer "F.Fab"))
    (pad "1" smd roundrect (at -0.7 0 90) (size 0.8 1) (layers "F.Cu" "F.Paste" "F.Mask") (roundrect_rratio 0.2)
      (net 136 "Net-(FB3-Pad1)") (pintype "passive"))
    (pad "2" smd roundrect (at 0.7 0 90) (size 0.8 1) (layers "F.Cu" "F.Paste" "F.Mask") (roundrect_rratio 0.2)
      (net 77 "GNDD") (pintype "passive"))
  )
	(footprint "antmicro-footprints:Conn_JST_SH_1x4_BM04B-SRSS-TB-LF-SN" (layer "F.Cu")
    (at 185.625 102.75)
    (property "Author" "Antmicro")
    (property "License" "Apache-2.0")
    (property "MPN" "BM04B-SRSS-TB(LF)(SN) ")
    (property "Manufacturer" "JST Automotive Connectors")
    (property "Sheetfile" "d1600e-psu-breakout-board.kicad_sch")
    (property "Sheetname" "")
    (property "ki_description" "Pin Header, Top Entry, Wire-to-Board, 1 mm, 1 Rows, 4 Contacts, Surface Mount, SR")
    (property "ki_keywords" "VERTICAL, SMT, WIRE-BOARD, CONNECTOR")
    (attr smd)
    (fp_text reference "J3" (at 2.925 0.55 90) (layer "F.SilkS")
        (effects (font (size 0.7 0.7) (thickness 0.15)) (justify left bottom))
    )
    (fp_text value "JST_SH_1x4_BM04B-SRSS-TB-LF-SN" (at -3.25 5) (layer "F.Fab")
        (effects (font (size 0.7 0.7) (thickness 0.15)) (justify left bottom))
    )
    (fp_text user "Author: Antmicro" (at -3.25 7) (layer "F.Fab") hide
        (effects (font (size 0.7 0.7) (thickness 0.15)) (justify left bottom))
    )
    (fp_text user "License: Apache-2.0" (at -3.25 9.4) (layer "F.Fab") hide
        (effects (font (size 0.7 0.7) (thickness 0.15)) (justify left bottom))
    )
    (fp_text user "${REFERENCE}" (at -3.25 8.2) (layer "F.Fab") hide
        (effects (font (size 0.7 0.7) (thickness 0.15)) (justify left bottom))
    )
    (fp_line (start -1.125 -2.999) (end -1.125 -2.201)
      (stroke (width 0.15) (type solid)) (layer "F.SilkS"))
    (fp_line (start -1.125 2.999) (end -1.125 2.201)
      (stroke (width 0.15) (type solid)) (layer "F.SilkS"))
    (fp_line (start -0.251 -2.999) (end -1.125 -2.999)
      (stroke (width 0.15) (type solid)) (layer "F.SilkS"))
    (fp_line (start -0.251 2.999) (end -1.125 2.999)
      (stroke (width 0.15) (type solid)) (layer "F.SilkS"))
    (fp_line (start 1.774 -1.7) (end 1.774 1.702)
      (stroke (width 0.15) (type solid)) (layer "F.SilkS"))
    (fp_circle (center -1.6 -2.1) (end -1.55 -2.1)
      (stroke (width 0.15) (type solid)) (fill solid) (layer "F.SilkS"))
    (fp_rect (start -2.05 -3.95) (end 2.05 3.95)
      (stroke (width 0.05) (type solid)) (fill none) (layer "F.CrtYd"))
    (fp_rect (start -1.8 -3) (end 1.8 3)
      (stroke (width 0.15) (type solid)) (fill none) (layer "F.Fab"))
    (pad "1" smd roundrect (at -1.45 -1.5 270) (size 0.6 1.55) (layers "F.Cu" "F.Paste" "F.Mask") (roundrect_rratio 0.25)
      (net 20 "Net-(J3-Pad1)") (pintype "passive"))
    (pad "2" smd roundrect (at -1.45 -0.5 270) (size 0.6 1.55) (layers "F.Cu" "F.Paste" "F.Mask") (roundrect_rratio 0.25)
      (net 99 "SDA_CON") (pintype "passive"))
    (pad "3" smd roundrect (at -1.45 0.5 270) (size 0.6 1.55) (layers "F.Cu" "F.Paste" "F.Mask") (roundrect_rratio 0.25)
      (net 17 "SCL") (pintype "passive"))
    (pad "4" smd roundrect (at -1.45 1.5 270) (size 0.6 1.55) (layers "F.Cu" "F.Paste" "F.Mask") (roundrect_rratio 0.25)
      (net 4 "GND") (pintype "passive"))
    (pad "MP" smd roundrect (at 1.075 -2.8 270) (size 1.2 1.8) (layers "F.Cu" "F.Paste" "F.Mask") (roundrect_rratio 0.25)
      (net 91 "unconnected-(J3-PadMP)") (pintype "passive+no_connect"))
    (pad "MP" smd roundrect (at 1.075 2.8 270) (size 1.2 1.8) (layers "F.Cu" "F.Paste" "F.Mask") (roundrect_rratio 0.25)
      (net 91 "unconnected-(J3-PadMP)") (pintype "passive+no_connect"))
  )
	(footprint "antmicro-footprints:R_0402_1005Metric" (layer "F.Cu")
    (at 180.3 109.65 -90)
    (descr "Resistor SMD 0402")
    (tags "resistor SMD 0402")
    (property "Author" "Antmicro")
    (property "License" "Apache-2.0")
    (property "MPN" "CR0402-FX-3300GLF")
    (property "Manufacturer" "Bourns")
    (property "Sheetfile" "ftdi-module.kicad_sch")
    (property "Sheetname" "FTDI")
    (property "Tolerance" "1%")
    (property "Val" "330R")
    (property "ki_description" "SMD Chip Resistor, 330 ohm, ± 1%, 62.5 mW, 0402 [1005 Metric], Thick Film, General Purpose")
    (property "ki_keywords" "0402, SMT, RESISTOR, PASSIVE")
    (attr smd)
    (fp_text reference "R7" (at 1.9 0.45 -90) (layer "F.SilkS")
        (effects (font (size 0.7 0.7) (thickness 0.15)) (justify left bottom))
    )
    (fp_text value "R_330R_0402" (at -1.011843 1.772047 -90) (layer "F.Fab")
        (effects (font (size 0.7 0.7) (thickness 0.15)) (justify left bottom))
    )
    (fp_text user "License: Apache-2.0" (at -0.95 5.169 -90) (layer "F.Fab") hide
        (effects (font (size 0.7 0.7) (thickness 0.15)) (justify left bottom))
    )
    (fp_text user "Author: Antmicro" (at -0.95 4.169 -90) (layer "F.Fab") hide
        (effects (font (size 0.7 0.7) (thickness 0.15)) (justify left bottom))
    )
    (fp_text user "${REFERENCE}" (at -0.95 3.168 -90) (layer "F.Fab") hide
        (effects (font (size 0.7 0.7) (thickness 0.15)) (justify left bottom))
    )
    (fp_rect (start -0.925 -0.47) (end 0.925 0.47)
      (stroke (width 0.05) (type default)) (fill none) (layer "F.CrtYd"))
    (fp_rect (start -0.5 -0.25) (end 0.5 0.25)
      (stroke (width 0.15) (type solid)) (fill none) (layer "F.Fab"))
    (pad "1" smd roundrect (at -0.48 0 270) (size 0.59 0.64) (layers "F.Cu" "F.Paste" "F.Mask") (roundrect_rratio 0.25)
      (net 76 "VCC3V3_USB") (pintype "passive"))
    (pad "2" smd roundrect (at 0.48 0 270) (size 0.59 0.64) (layers "F.Cu" "F.Paste" "F.Mask") (roundrect_rratio 0.25)
      (net 35 "Net-(D2-A)") (pintype "passive"))
  )
	(footprint "antmicro-footprints:R_0603_1608Metric" (layer "F.Cu")
    (at 183.2 116.05 -90)
    (descr "Resistor SMD 0603")
    (tags "resistor SMD 0603")
    (property "Author" "Antmicro")
    (property "Current" "1A")
    (property "License" "Apache-2.0")
    (property "MPN" "CR0603-J/-000ELF")
    (property "Manufacturer" "Bourns")
    (property "Sheetfile" "ftdi-module.kicad_sch")
    (property "Sheetname" "FTDI")
    (property "Tolerance" "")
    (property "Val" "0R")
    (property "ki_description" "Zero Ohm Resistor, Jumper, 0603 [1608 Metric], Thick Film, 100 mW, 1 A, Surface Mount Device, CR")
    (property "ki_keywords" "0603, SMT, RESISTOR, PASSIVE")
    (attr smd)
    (fp_text reference "R8" (at -1.25 -1 -90) (layer "F.SilkS")
        (effects (font (size 0.7 0.7) (thickness 0.15)) (justify left bottom))
    )
    (fp_text value "R_0R_0603" (at 0 1.6 -90) (layer "F.Fab")
        (effects (font (size 0.7 0.7) (thickness 0.15)) (justify left bottom))
    )
    (fp_text user "${REFERENCE}" (at -1.25 3.898 -90) (layer "F.Fab") hide
        (effects (font (size 0.7 0.7) (thickness 0.15)) (justify left bottom))
    )
    (fp_text user "License: Apache-2.0" (at -1.25 5.9 -90) (layer "F.Fab") hide
        (effects (font (size 0.7 0.7) (thickness 0.15)) (justify left bottom))
    )
    (fp_text user "Author: Antmicro" (at -1.25 4.9 -90) (layer "F.Fab") hide
        (effects (font (size 0.7 0.7) (thickness 0.15)) (justify left bottom))
    )
    (fp_line (start -0.15 -0.4) (end 0.15 -0.4)
      (stroke (width 0.15) (type solid)) (layer "F.SilkS"))
    (fp_line (start -0.15 0.4) (end 0.15 0.4)
      (stroke (width 0.15) (type solid)) (layer "F.SilkS"))
    (fp_rect (start -1.25 -0.65) (end 1.25 0.65)
      (stroke (width 0.05) (type solid)) (fill none) (layer "F.CrtYd"))
    (fp_rect (start -0.8 -0.4) (end 0.8 0.4)
      (stroke (width 0.15) (type solid)) (fill none) (layer "F.Fab"))
    (pad "1" smd roundrect (at -0.7 0 270) (size 0.8 1) (layers "F.Cu" "F.Paste" "F.Mask") (roundrect_rratio 0.2)
      (net 10 "VBUS") (pintype "passive"))
    (pad "2" smd roundrect (at 0.7 0 270) (size 0.8 1) (layers "F.Cu" "F.Paste" "F.Mask") (roundrect_rratio 0.2)
      (net 3 "VCC5V0_USB") (pintype "passive"))
  )
	(footprint "antmicro-footprints:R_0402_1005Metric" (layer "F.Cu")
    (at 182.25 99.515 -90)
    (descr "Resistor SMD 0402")
    (tags "resistor SMD 0402")
    (property "Author" "Antmicro")
    (property "Current" "1A")
    (property "DNP" "DNP")
    (property "License" "Apache-2.0")
    (property "MPN" "ERJ2GE0R00X")
    (property "Manufacturer" "Panasonic")
    (property "Sheetfile" "d1600e-psu-breakout-board.kicad_sch")
    (property "Sheetname" "")
    (property "Tolerance" "")
    (property "Val" "0R")
    (property "dnp" "")
    (property "exclude_from_bom" "")
    (property "ki_description" "SMD Chip Resistor, Jumper, 0 ohm, 100 mW, 0402 [1005 Metric], Thick Film, General Purpose")
    (property "ki_keywords" "0402, SMT, RESISTOR, PASSIVE")
    (attr smd exclude_from_bom)
    (fp_text reference "R10" (at -0.025 0.93 90) (layer "F.SilkS")
        (effects (font (size 0.7 0.7) (thickness 0.15)))
    )
    (fp_text value "R_0R_0402" (at 0 1.17 90) (layer "F.Fab") hide
        (effects (font (size 1 1) (thickness 0.15)))
    )
    (fp_text user "Author: Antmicro" (at -0.95 4.169 -90) (layer "F.Fab") hide
        (effects (font (size 0.7 0.7) (thickness 0.15)) (justify left bottom))
    )
    (fp_text user "${REFERENCE}" (at 0 0 90) (layer "F.Fab")
        (effects (font (size 0.7 0.7) (thickness 0.15)))
    )
    (fp_text user "License: Apache-2.0" (at -0.95 5.169 -90) (layer "F.Fab") hide
        (effects (font (size 0.7 0.7) (thickness 0.15)) (justify left bottom))
    )
    (fp_rect (start -0.925 -0.47) (end 0.925 0.47)
      (stroke (width 0.05) (type default)) (fill none) (layer "F.CrtYd"))
    (fp_rect (start -0.5 -0.25) (end 0.5 0.25)
      (stroke (width 0.15) (type solid)) (fill none) (layer "F.Fab"))
    (pad "1" smd roundrect (at -0.48 0 270) (size 0.59 0.64) (layers "F.Cu" "F.Paste" "F.Mask") (roundrect_rratio 0.25)
      (net 1 "VCC3V3") (pintype "passive"))
    (pad "2" smd roundrect (at 0.48 0 270) (size 0.59 0.64) (layers "F.Cu" "F.Paste" "F.Mask") (roundrect_rratio 0.25)
      (net 20 "Net-(J3-Pad1)") (pintype "passive"))
  )
)
